# T6G (Grand Teton) — schematic netlist excerpt (pin names and nets, part order shuffled) for the footprints in the layout excerpt that follows; sources: Cadence DE-HDL packaged netlist, KiCad conversion of 04192023_DAF0TMB3IC0_F0TG_MB_C_brd_V02_OCP.brd

PU30  ISL99390FRZTR5935  ISL99390FRZ-TR5935 IC  pkg QFN21_6X5XB  page 215
  VOS  = PVDDCR_SOC_P1_VOS1
  AGND  = GND
  VCC  = PVDDCR_SOC_P1_VCC1
  PVCC  = PVDDCR_CPU0_P1_PVCC
  PGND1  = GND
  GL1  = NC_PVDDCR_SOC_P1_GL1_1
  PGND2  = GND
  SW  = SW_PVDDCR_SOC_P1_SW1
  VIN1  = SW_P12V_AUX_PVDDCR_SOC_P1_FLT
  VIN2  = SW_P12V_AUX_PVDDCR_SOC_P1_FLT
  DNC  = NC_PVDDCR_SOC_P1_DNC1
  PHASE  = SW_PVDDCR_SOC_P1_PH1
  BOOT  = SW_PVDDCR_SOC_P1_BOOT1
  PWM  = PVDDCR_SOC_P1_PWM1
  EN  = PVDDCR_SOC_P1_VCC1
  TOUT_FLT  = PVDDCR_SOC_P1_TEMP1
  LSET  = PVDDCR_SOC_P1_LSET1
  IOUT  = PVDDCR_SOC_P1_IMON1
  REFIN  = PVDDCR_CPU0_P1_VCCS
  PGND3  = GND
  GL2  = NC_PVDDCR_SOC_P1_GL2_1

(kicad_pcb
	(version 20260206)
	(generator "pcbnew")
	(generator_version "10.0")
	(general
		(thickness 1.6)
		(legacy_teardrops no)
	)
	(paper "A4")
	(title_block
		(title "04192023_DAF0TMB3IC0_F0TG_MB_C_brd_V02_OCP.brd")
		(comment 1 "Grand Teton / footprints 1936-1936 of 8354")
	)
	(layers
		(0 "F.Cu" signal "TOP")
		(4 "In1.Cu" signal "GND")
		(6 "In2.Cu" signal "IN1")
		(8 "In3.Cu" signal "GND1")
		(10 "In4.Cu" signal "IN2")
		(12 "In5.Cu" signal "GND2")
		(14 "In6.Cu" signal "IN3")
		(16 "In7.Cu" signal "GND3")
		(18 "In8.Cu" signal "VCC")
		(20 "In9.Cu" signal "VCC1")
		(22 "In10.Cu" signal "GND4")
		(24 "In11.Cu" signal "IN4")
		(26 "In12.Cu" signal "GND5")
		(28 "In13.Cu" signal "IN5")
		(30 "In14.Cu" signal "GND6")
		(32 "In15.Cu" signal "IN6")
		(34 "In16.Cu" signal "GND7")
		(2 "B.Cu" signal "BOTTOM")
		(9 "F.Adhes" user "F.Adhesive")
		(11 "B.Adhes" user "B.Adhesive")
		(13 "F.Paste" user "Package Geometry/Pastemask Top")
		(15 "B.Paste" user "Package Geometry/Pastemask Bottom")
		(5 "F.SilkS" user "Ref Des/Silkscreen Top")
		(7 "B.SilkS" user "Ref Des/Silkscreen Bottom")
		(1 "F.Mask" user "Board Geometry/Soldermask Top")
		(3 "B.Mask" user "Board Geometry/Soldermask Bottom")
		(17 "Dwgs.User" user "User.Drawings")
		(19 "Cmts.User" user "User.Comments")
		(21 "Eco1.User" user "User.Eco1")
		(23 "Eco2.User" user "User.Eco2")
		(25 "Edge.Cuts" user "Board Geometry/Outline")
		(27 "Margin" user)
		(31 "F.CrtYd" user "Package Geometry/Place Bound Top")
		(29 "B.CrtYd" user "Package Geometry/Place Bound Bottom")
		(35 "F.Fab" user "Ref Des/Assembly Top")
		(33 "B.Fab" user "Ref Des/Assembly Bottom")
	)
	(footprint ""
		(layer "F.Cu")
		(at 115.68557 -171.923456 180)
		(property "Reference" "PU30"
			(at 2.49682 -7.206742 0)
			(unlocked yes)
			(layer "F.SilkS")
			(effects
				(font
					(size 0.7874 0.5842)
					(thickness 0.1524)
				)
				(justify left)
			)
		)
		(property "Value" ""
			(at 0 0 180)
			(layer "F.Fab")
			(effects
				(font
					(size 1.27 1.27)
				)
			)
		)
		(duplicate_pad_numbers_are_jumpers no)
		(fp_line
			(start 2.500122 2.999994)
			(end 2.2987 2.999994)
			(stroke
				(width 0.1524)
				(type default)
			)
			(layer "F.SilkS")
		)
		(fp_line
			(start 2.500122 2.339594)
			(end 2.500122 2.999994)
			(stroke
				(width 0.1524)
				(type default)
			)
			(layer "F.SilkS")
		)
		(fp_line
			(start 2.500122 -2.999994)
			(end 2.500122 -2.44348)
			(stroke
				(width 0.1524)
				(type default)
			)
			(layer "F.SilkS")
		)
		(fp_line
			(start 2.31394 -2.999994)
			(end 2.500122 -2.999994)
			(stroke
				(width 0.1524)
				(type default)
			)
			(layer "F.SilkS")
		)
		(fp_line
			(start -2.2987 2.999994)
			(end -2.500122 2.999994)
			(stroke
				(width 0.1524)
				(type default)
			)
			(layer "F.SilkS")
		)
		(fp_line
			(start -2.500122 2.999994)
			(end -2.500122 2.339594)
			(stroke
				(width 0.1524)
				(type default)
			)
			(layer "F.SilkS")
		)
		(fp_line
			(start -2.500122 0.6604)
			(end -2.500122 0.229108)
			(stroke
				(width 0.1524)
				(type default)
			)
			(layer "F.SilkS")
		)
		(fp_line
			(start -2.500122 -2.529078)
			(end -2.500122 -2.999994)
			(stroke
				(width 0.1524)
				(type default)
			)
			(layer "F.SilkS")
		)
		(fp_line
			(start -2.500122 -2.999994)
			(end -2.24409 -2.999994)
			(stroke
				(width 0.1524)
				(type default)
			)
			(layer "F.SilkS")
		)
		(fp_poly
			(pts
				(xy -2.781554 -2.38633) (xy -3.455162 -2.610866) (xy -3.00609 -3.059938)
			)
			(stroke
				(width 0)
				(type default)
			)
			(fill yes)
			(layer "F.SilkS")
		)
		(fp_line
			(start 2.500122 2.999994)
			(end -2.500122 2.999994)
			(stroke
				(width 0.1)
				(type default)
			)
			(layer "F.Fab")
		)
		(fp_line
			(start 2.500122 -2.999994)
			(end 2.500122 2.999994)
			(stroke
				(width 0.1)
				(type default)
			)
			(layer "F.Fab")
		)
		(fp_line
			(start -2.500122 2.999994)
			(end -2.500122 -2.999994)
			(stroke
				(width 0.1)
				(type default)
			)
			(layer "F.Fab")
		)
		(fp_line
			(start -2.500122 -2.999994)
			(end 2.500122 -2.999994)
			(stroke
				(width 0.1)
				(type default)
			)
			(layer "F.Fab")
		)
		(fp_poly
			(pts
				(xy -4.218432 -2.783078) (xy -4.218432 -1.767078) (xy -3.202432 -2.275078)
			)
			(stroke
				(width 0)
				(type default)
			)
			(fill yes)
			(layer "F.Fab")
		)
		(pad "1" smd rect
			(at -2.400046 -2.275078 270)
			(size 0.2286 0.6096)
			(layers "F.Cu" "F.Mask" "F.Paste")
			(net "PVDDCR_SOC_P1_VOS1")
		)
		(pad "2" smd rect
			(at -2.400046 -1.82499 270)
			(size 0.2286 0.6096)
			(layers "F.Cu" "F.Mask" "F.Paste")
			(net "GND")
		)
		(pad "3" smd rect
			(at -2.400046 -1.374902 270)
			(size 0.2286 0.6096)
			(layers "F.Cu" "F.Mask" "F.Paste")
			(net "PVDDCR_SOC_P1_VCC1")
		)
		(pad "4" smd rect
			(at -2.400046 -0.925068 270)
			(size 0.2286 0.6096)
			(layers "F.Cu" "F.Mask" "F.Paste")
			(net "PVDDCR_CPU0_P1_PVCC")
		)
		(pad "5" smd rect
			(at -2.400046 -0.47498 270)
			(size 0.2286 0.6096)
			(layers "F.Cu" "F.Mask" "F.Paste")
			(net "GND")
		)
		(pad "6" smd rect
			(at -2.400046 -0.024892 270)
			(size 0.2286 0.6096)
			(layers "F.Cu" "F.Mask" "F.Paste")
			(net "NC_PVDDCR_SOC_P1_GL1_1")
		)
		(pad "7_9-20_24" smd circle
			(at 0 1.150112 270)
			(size 0 0)
			(layers "F.Cu" "F.Mask" "F.Paste")
			(net "GND")
		)
		(pad "10_19" smd rect
			(at 0 2.899918 270)
			(size 0.6096 4.318)
			(layers "F.Cu" "F.Mask" "F.Paste")
			(net "SW_PVDDCR_SOC_P1_SW1")
		)
		(pad "25_29" smd rect
			(at 1.549908 -1.279906 90)
			(size 2.0574 2.3114)
			(layers "F.Cu" "F.Mask" "F.Paste")
			(net "SW_P12V_AUX_PVDDCR_SOC_P1_FLT")
		)
		(pad "30" smd rect
			(at 2.05994 -2.899918 180)
			(size 0.2286 0.6096)
			(layers "F.Cu" "F.Mask" "F.Paste")
			(net "SW_P12V_AUX_PVDDCR_SOC_P1_FLT")
		)
		(pad "31" smd rect
			(at 1.610106 -2.899918 180)
			(size 0.2286 0.6096)
			(layers "F.Cu" "F.Mask" "F.Paste")
			(net "NC_PVDDCR_SOC_P1_DNC1")
		)
		(pad "32" smd rect
			(at 1.160018 -2.899918 180)
			(size 0.2286 0.6096)
			(layers "F.Cu" "F.Mask" "F.Paste")
			(net "SW_PVDDCR_SOC_P1_PH1")
		)
		(pad "33" smd rect
			(at 0.70993 -2.899918 180)
			(size 0.2286 0.6096)
			(layers "F.Cu" "F.Mask" "F.Paste")
			(net "SW_PVDDCR_SOC_P1_BOOT1")
		)
		(pad "34" smd rect
			(at 0.260096 -2.899918 180)
			(size 0.2286 0.6096)
			(layers "F.Cu" "F.Mask" "F.Paste")
			(net "PVDDCR_SOC_P1_PWM1")
		)
		(pad "35" smd rect
			(at -0.189992 -2.899918 180)
			(size 0.2286 0.6096)
			(layers "F.Cu" "F.Mask" "F.Paste")
			(net "PVDDCR_SOC_P1_VCC1")
		)
		(pad "36" smd rect
			(at -0.64008 -2.899918 180)
			(size 0.2286 0.6096)
			(layers "F.Cu" "F.Mask" "F.Paste")
			(net "PVDDCR_SOC_P1_TEMP1")
		)
		(pad "37" smd rect
			(at -1.089914 -2.899918 180)
			(size 0.2286 0.6096)
			(layers "F.Cu" "F.Mask" "F.Paste")
			(net "PVDDCR_SOC_P1_LSET1")
		)
		(pad "38" smd rect
			(at -1.540002 -2.899918 180)
			(size 0.2286 0.6096)
			(layers "F.Cu" "F.Mask" "F.Paste")
			(net "PVDDCR_SOC_P1_IMON1")
		)
		(pad "39" smd rect
			(at -1.99009 -2.899918 180)
			(size 0.2286 0.6096)
			(layers "F.Cu" "F.Mask" "F.Paste")
			(net "PVDDCR_CPU0_P1_VCCS")
		)
		(pad "40" smd rect
			(at -0.87503 -1.27508 180)
			(size 1.7526 1.9558)
			(layers "F.Cu" "F.Mask" "F.Paste")
			(net "GND")
		)
		(pad "41" smd rect
			(at -1.525016 0.249936 90)
			(size 0.3048 0.4572)
			(layers "F.Cu" "F.Mask" "F.Paste")
			(net "NC_PVDDCR_SOC_P1_GL2_1")
		)
		(zone
			(layer "F.Cu")
			(hatch none 0.5)
			(connect_pads
				(clearance 0)
			)
			(min_thickness 0.25)
			(keepout
				(tracks not_allowed)
				(vias allowed)
				(pads allowed)
				(copperpour not_allowed)
				(footprints allowed)
			)
			(placement
				(enabled no)
				(sheetname "")
			)
			(fill
				(thermal_gap 0.5)
				(thermal_bridge_width 0.5)
				(island_removal_mode 0)
			)
			(polygon
				(pts
					(xy 118.185692 -174.467774) (xy 118.185692 -174.17415) (xy 113.185448 -174.17415) (xy 113.185448 -174.467774)
					(xy 113.47577 -174.467774) (xy 117.89537 -174.467774)
				)
			)
		)
		(zone
			(layer "F.Cu")
			(hatch none 0.5)
			(connect_pads
				(clearance 0)
			)
			(min_thickness 0.25)
			(keepout
				(tracks not_allowed)
				(vias allowed)
				(pads allowed)
				(copperpour not_allowed)
				(footprints allowed)
			)
			(placement
				(enabled no)
				(sheetname "")
			)
			(fill
				(thermal_gap 0.5)
				(thermal_bridge_width 0.5)
				(island_removal_mode 0)
			)
			(polygon
				(pts
					(xy 115.6335 -171.677076) (xy 115.6335 -169.619676) (xy 117.4877 -169.619676) (xy 117.4877 -169.860722)
					(xy 117.730016 -169.860722) (xy 117.730016 -169.379138) (xy 113.800636 -169.379138) (xy 113.800636 -169.56405)
					(xy 115.342162 -169.56405) (xy 115.342162 -171.72305) (xy 113.185448 -171.72305) (xy 113.185448 -171.972732)
					(xy 115.369848 -171.972732) (xy 115.6335 -171.70908)
				)
			)
		)
	)
)
